(kicad_pcb
	(version 20260206)
	(generator "pcbnew")
	(generator_version "10.0")
	(general
		(thickness 1.6)
		(legacy_teardrops no)
	)
	(paper "A4")
	(title_block
		(title "fcb — 12433-1M.1206WZS1330.brd")
		(comment 1 "Open Vault / Knox (Wiwynn) / footprints 437-442 of 495")
	)
	(layers
		(0 "F.Cu" signal "TOP")
		(4 "In1.Cu" signal "L2GND")
		(6 "In2.Cu" signal "L3VCC")
		(2 "B.Cu" signal "BOTTOM")
		(9 "F.Adhes" user "F.Adhesive")
		(11 "B.Adhes" user "B.Adhesive")
		(13 "F.Paste" user "Package Geometry/Pastemask Top")
		(15 "B.Paste" user "Package Geometry/Pastemask Bottom")
		(5 "F.SilkS" user "Ref Des/Silkscreen Top")
		(7 "B.SilkS" user "Ref Des/Silkscreen Bottom")
		(1 "F.Mask" user "Board Geometry/Soldermask Top")
		(3 "B.Mask" user "Board Geometry/Soldermask Bottom")
		(17 "Dwgs.User" user "User.Drawings")
		(19 "Cmts.User" user "User.Comments")
		(21 "Eco1.User" user "User.Eco1")
		(23 "Eco2.User" user "User.Eco2")
		(25 "Edge.Cuts" user "Board Geometry/Outline")
		(27 "Margin" user)
		(31 "F.CrtYd" user "Package Geometry/Place Bound Top")
		(29 "B.CrtYd" user "Package Geometry/Place Bound Bottom")
		(35 "F.Fab" user "Ref Des/Assembly Top")
		(33 "B.Fab" user "Ref Des/Assembly Bottom")
	)
	(footprint ""
		(layer "F.Cu")
		(at 40.64 -410.591)
		(property "Reference" "PR32"
			(at 0 0 0)
			(layer "F.SilkS")
			(hide yes)
			(effects
				(font
					(size 1.27 1.27)
				)
			)
		)
		(property "Value" "D0005RL1632F-GP-U"
			(at 3.2258 1.2954 0)
			(unlocked yes)
			(layer "F.Fab")
			(hide yes)
			(effects
				(font
					(size 1.016 1.016)
					(thickness 0.1524)
				)
			)
		)
		(property "Device Type" "RL3115-4PH45"
			(at 3.2258 -0.2286 0)
			(unlocked yes)
			(layer "F.Fab")
			(hide yes)
			(effects
				(font
					(size 1.016 1.016)
					(thickness 0.1524)
				)
			)
		)
		(duplicate_pad_numbers_are_jumpers no)
		(fp_line
			(start -2.0574 -1.7653)
			(end -2.0574 -0.4064)
			(stroke
				(width 0.3302)
				(type default)
			)
			(layer "F.SilkS")
		)
		(fp_line
			(start -1.9685 -1.651)
			(end 1.9685 -1.651)
			(stroke
				(width 0.1524)
				(type default)
			)
			(layer "F.SilkS")
		)
		(fp_line
			(start -1.9685 1.651)
			(end -1.9685 -1.651)
			(stroke
				(width 0.1524)
				(type default)
			)
			(layer "F.SilkS")
		)
		(fp_line
			(start -0.5334 -1.7653)
			(end -2.0574 -1.7653)
			(stroke
				(width 0.3302)
				(type default)
			)
			(layer "F.SilkS")
		)
		(fp_line
			(start 1.9685 -1.651)
			(end 1.9685 1.651)
			(stroke
				(width 0.1524)
				(type default)
			)
			(layer "F.SilkS")
		)
		(fp_line
			(start 1.9685 1.651)
			(end -1.9685 1.651)
			(stroke
				(width 0.1524)
				(type default)
			)
			(layer "F.SilkS")
		)
		(fp_poly
			(pts
				(xy -0.561594 -1.726946) (xy -0.053594 -2.234946) (xy -1.069594 -2.234946)
			)
			(stroke
				(width 0)
				(type default)
			)
			(fill yes)
			(layer "F.SilkS")
		)
		(fp_rect
			(start -1.524 0.7493)
			(end 1.524 -0.7493)
			(stroke
				(width 0)
				(type default)
			)
			(fill no)
			(layer "F.CrtYd")
		)
		(fp_poly
			(pts
				(xy -2.2225 1.905) (xy -2.2225 -1.905) (xy 2.2225 -1.905) (xy 2.2225 -0.7493) (xy -1.524 -0.7493)
				(xy -1.524 0.7493) (xy 1.524 0.7493) (xy 1.524 -0.7366) (xy 2.2225 -0.7366) (xy 2.2225 1.905)
			)
			(stroke
				(width 0)
				(type default)
			)
			(fill no)
			(layer "F.CrtYd")
		)
		(fp_rect
			(start -2.2225 1.905)
			(end 2.2225 -1.905)
			(stroke
				(width 0)
				(type default)
			)
			(fill no)
			(layer "F.Fab")
		)
		(pad "1" smd rect
			(at -0.5715 -0.813562)
			(size 2.286 1.143)
			(layers "F.Cu" "F.Mask" "F.Paste")
			(net "P12V_AUX")
		)
		(pad "2" smd rect
			(at -0.5715 0.813562)
			(size 2.286 1.143)
			(layers "F.Cu" "F.Mask" "F.Paste")
			(net "P12V_SENSE_TRACE")
		)
		(pad "3" smd rect
			(at 1.334008 -0.813562)
			(size 0.762 1.143)
			(layers "F.Cu" "F.Mask" "F.Paste")
			(net "SENSE+_R4")
		)
		(pad "4" smd rect
			(at 1.334008 0.813562)
			(size 0.762 1.143)
			(layers "F.Cu" "F.Mask" "F.Paste")
			(net "SENSE-_R4")
		)
		(zone
			(layer "F.Cu")
			(hatch none 0.5)
			(connect_pads
				(clearance 0)
			)
			(min_thickness 0.25)
			(keepout
				(tracks not_allowed)
				(vias allowed)
				(pads allowed)
				(copperpour not_allowed)
				(footprints allowed)
			)
			(placement
				(enabled no)
				(sheetname "")
			)
			(fill
				(thermal_gap 0.5)
				(thermal_bridge_width 0.5)
				(island_removal_mode 0)
			)
			(polygon
				(pts
					(xy 41.2115 -410.833062) (xy 41.593008 -410.833062) (xy 41.593008 -411.3403) (xy 41.2115 -411.3403)
				)
			)
		)
		(zone
			(layer "F.Cu")
			(hatch none 0.5)
			(connect_pads
				(clearance 0)
			)
			(min_thickness 0.25)
			(keepout
				(tracks allowed)
				(vias not_allowed)
				(pads allowed)
				(copperpour not_allowed)
				(footprints allowed)
			)
			(placement
				(enabled no)
				(sheetname "")
			)
			(fill
				(thermal_gap 0.5)
				(thermal_bridge_width 0.5)
				(island_removal_mode 0)
			)
			(polygon
				(pts
					(xy 41.2115 -410.833062) (xy 41.593008 -410.833062) (xy 41.593008 -411.3403) (xy 41.2115 -411.3403)
				)
			)
		)
		(zone
			(layer "F.Cu")
			(hatch none 0.5)
			(connect_pads
				(clearance 0)
			)
			(min_thickness 0.25)
			(keepout
				(tracks allowed)
				(vias not_allowed)
				(pads allowed)
				(copperpour not_allowed)
				(footprints allowed)
			)
			(placement
				(enabled no)
				(sheetname "")
			)
			(fill
				(thermal_gap 0.5)
				(thermal_bridge_width 0.5)
				(island_removal_mode 0)
			)
			(polygon
				(pts
					(xy 41.2115 -409.8417) (xy 41.593008 -409.8417) (xy 41.593008 -410.348938) (xy 41.2115 -410.348938)
				)
			)
		)
		(zone
			(layer "F.Cu")
			(hatch none 0.5)
			(connect_pads
				(clearance 0)
			)
			(min_thickness 0.25)
			(keepout
				(tracks not_allowed)
				(vias allowed)
				(pads allowed)
				(copperpour not_allowed)
				(footprints allowed)
			)
			(placement
				(enabled no)
				(sheetname "")
			)
			(fill
				(thermal_gap 0.5)
				(thermal_bridge_width 0.5)
				(island_removal_mode 0)
			)
			(polygon
				(pts
					(xy 41.2115 -409.8417) (xy 41.593008 -409.8417) (xy 41.593008 -410.348938) (xy 41.2115 -410.348938)
				)
			)
		)
	)
	(footprint ""
		(layer "F.Cu")
		(at 30.3022 -253.8984 180)
		(property "Reference" "R46"
			(at 0 0 180)
			(layer "F.SilkS")
			(hide yes)
			(effects
				(font
					(size 1.27 1.27)
				)
			)
		)
		(property "Value" "0R2J-2-GP"
			(at 0.064008 -3.993896 180)
			(unlocked yes)
			(layer "F.Fab")
			(hide yes)
			(effects
				(font
					(size 1.016 1.016)
					(thickness 0.1524)
				)
			)
		)
		(property "Device Type" "R402H16"
			(at 0.064008 -5.517896 180)
			(unlocked yes)
			(layer "F.Fab")
			(hide yes)
			(effects
				(font
					(size 1.016 1.016)
					(thickness 0.1524)
				)
			)
		)
		(duplicate_pad_numbers_are_jumpers no)
		(fp_line
			(start 0.508 -0.9398)
			(end -0.508 -0.9398)
			(stroke
				(width 0.1524)
				(type default)
			)
			(layer "F.SilkS")
		)
		(fp_line
			(start -0.508 -0.9398)
			(end -0.508 0.9398)
			(stroke
				(width 0.1524)
				(type default)
			)
			(layer "F.SilkS")
		)
		(fp_rect
			(start -0.508 0.9398)
			(end 0.508 -0.9398)
			(stroke
				(width 0)
				(type default)
			)
			(fill no)
			(layer "F.CrtYd")
		)
		(fp_rect
			(start -0.508 0.9398)
			(end 0.508 -0.9398)
			(stroke
				(width 0)
				(type default)
			)
			(fill no)
			(layer "F.Fab")
		)
		(pad "1" smd custom
			(at 0 -0.4445 180)
			(size 0.1397 0.1397)
			(layers "F.Cu" "F.Mask" "F.Paste")
			(net "I2C_C_SCL_EEPROM")
			(options
				(clearance outline)
				(anchor circle)
			)
			(primitives
				(gr_poly
					(pts
						(arc
							(start -0.1778 -0.2794)
							(mid -0.249642 -0.249642)
							(end -0.2794 -0.1778)
						)
						(arc
							(start -0.2794 0.1778)
							(mid -0.249642 0.249642)
							(end -0.1778 0.2794)
						)
						(arc
							(start 0.1778 0.2794)
							(mid 0.249642 0.249642)
							(end 0.2794 0.1778)
						)
						(arc
							(start 0.2794 -0.1778)
							(mid 0.249642 -0.249642)
							(end 0.1778 -0.2794)
						)
					)
					(width 0)
					(fill yes)
				)
			)
		)
		(pad "2" smd custom
			(at 0 0.4445 180)
			(size 0.1397 0.1397)
			(layers "F.Cu" "F.Mask" "F.Paste")
			(net "I2C_C_SCL")
			(options
				(clearance outline)
				(anchor circle)
			)
			(primitives
				(gr_poly
					(pts
						(arc
							(start -0.1778 -0.2794)
							(mid -0.249642 -0.249642)
							(end -0.2794 -0.1778)
						)
						(arc
							(start -0.2794 0.1778)
							(mid -0.249642 0.249642)
							(end -0.1778 0.2794)
						)
						(arc
							(start 0.1778 0.2794)
							(mid 0.249642 0.249642)
							(end 0.2794 0.1778)
						)
						(arc
							(start 0.2794 -0.1778)
							(mid 0.249642 -0.249642)
							(end 0.1778 -0.2794)
						)
					)
					(width 0)
					(fill yes)
				)
			)
		)
	)
	(footprint ""
		(layer "F.Cu")
		(at 17.9578 -150.114 -90)
		(property "Reference" "R72"
			(at 0 0 270)
			(layer "F.SilkS")
			(hide yes)
			(effects
				(font
					(size 1.27 1.27)
				)
			)
		)
		(property "Value" "27KR3F-GP"
			(at -0.0254 -2.5146 270)
			(unlocked yes)
			(layer "F.Fab")
			(hide yes)
			(effects
				(font
					(size 1.016 1.016)
					(thickness 0.1524)
				)
			)
		)
		(property "Device Type" "R603H22"
			(at -0.0254 -4.0386 270)
			(unlocked yes)
			(layer "F.Fab")
			(hide yes)
			(effects
				(font
					(size 1.016 1.016)
					(thickness 0.1524)
				)
			)
		)
		(duplicate_pad_numbers_are_jumpers no)
		(fp_line
			(start -0.4826 0)
			(end -0.2032 0)
			(stroke
				(width 0.2032)
				(type default)
			)
			(layer "F.SilkS")
		)
		(fp_line
			(start 0.2032 0)
			(end 0.4826 0)
			(stroke
				(width 0.2032)
				(type default)
			)
			(layer "F.SilkS")
		)
		(fp_rect
			(start -0.5842 1.3335)
			(end 0.5842 -1.3335)
			(stroke
				(width 0)
				(type default)
			)
			(fill no)
			(layer "F.CrtYd")
		)
		(fp_rect
			(start -0.5842 1.3335)
			(end 0.5842 -1.3335)
			(stroke
				(width 0)
				(type default)
			)
			(fill no)
			(layer "F.Fab")
		)
		(pad "1" smd custom
			(at 0 -0.762 270)
			(size 0.2159 0.2159)
			(layers "F.Cu" "F.Mask" "F.Paste")
			(net "FANIN_9")
			(options
				(clearance outline)
				(anchor circle)
			)
			(primitives
				(gr_poly
					(pts
						(arc
							(start -0.3302 -0.4318)
							(mid -0.402042 -0.402042)
							(end -0.4318 -0.3302)
						)
						(arc
							(start -0.4318 0.3302)
							(mid -0.402042 0.402042)
							(end -0.3302 0.4318)
						)
						(arc
							(start 0.3302 0.4318)
							(mid 0.402042 0.402042)
							(end 0.4318 0.3302)
						)
						(arc
							(start 0.4318 -0.3302)
							(mid 0.402042 -0.402042)
							(end 0.3302 -0.4318)
						)
					)
					(width 0)
					(fill yes)
				)
			)
		)
		(pad "2" smd custom
			(at 0 0.762 270)
			(size 0.2159 0.2159)
			(layers "F.Cu" "F.Mask" "F.Paste")
			(net "FAN_TACH9")
			(options
				(clearance outline)
				(anchor circle)
			)
			(primitives
				(gr_poly
					(pts
						(arc
							(start -0.3302 -0.4318)
							(mid -0.402042 -0.402042)
							(end -0.4318 -0.3302)
						)
						(arc
							(start -0.4318 0.3302)
							(mid -0.402042 0.402042)
							(end -0.3302 0.4318)
						)
						(arc
							(start 0.3302 0.4318)
							(mid 0.402042 0.402042)
							(end 0.4318 0.3302)
						)
						(arc
							(start 0.4318 -0.3302)
							(mid 0.402042 -0.402042)
							(end 0.3302 -0.4318)
						)
					)
					(width 0)
					(fill yes)
				)
			)
		)
	)
	(footprint ""
		(layer "F.Cu")
		(at 23.622 -364.4646 -90)
		(property "Reference" "PC3"
			(at 0 0 270)
			(layer "F.SilkS")
			(hide yes)
			(effects
				(font
					(size 1.27 1.27)
				)
			)
		)
		(property "Value" "SCD01U25V2KX-3GP"
			(at 1.1811 -2.7051 270)
			(unlocked yes)
			(layer "F.Fab")
			(hide yes)
			(effects
				(font
					(size 1.016 1.016)
					(thickness 0.1524)
				)
			)
		)
		(property "Device Type" "C402H22"
			(at 1.1811 -4.2291 270)
			(unlocked yes)
			(layer "F.Fab")
			(hide yes)
			(effects
				(font
					(size 1.016 1.016)
					(thickness 0.1524)
				)
			)
		)
		(duplicate_pad_numbers_are_jumpers no)
		(fp_rect
			(start -0.4318 0.9525)
			(end 0.4318 -0.9525)
			(stroke
				(width 0)
				(type default)
			)
			(fill no)
			(layer "F.CrtYd")
		)
		(fp_rect
			(start -0.4318 0.9525)
			(end 0.4318 -0.9525)
			(stroke
				(width 0)
				(type default)
			)
			(fill no)
			(layer "F.Fab")
		)
		(pad "1" smd custom
			(at 0 -0.4445 270)
			(size 0.1524 0.1524)
			(layers "F.Cu" "F.Mask" "F.Paste")
			(net "ADM1276_SS")
			(options
				(clearance outline)
				(anchor circle)
			)
			(primitives
				(gr_poly
					(pts
						(arc
							(start 0.3048 -0.2032)
							(mid 0.275042 -0.275042)
							(end 0.2032 -0.3048)
						)
						(arc
							(start -0.2032 -0.3048)
							(mid -0.275042 -0.275042)
							(end -0.3048 -0.2032)
						)
						(arc
							(start -0.3048 0.2032)
							(mid -0.275042 0.275042)
							(end -0.2032 0.3048)
						)
						(arc
							(start 0.2032 0.3048)
							(mid 0.275042 0.275042)
							(end 0.3048 0.2032)
						)
					)
					(width 0)
					(fill yes)
				)
			)
		)
		(pad "2" smd custom
			(at 0 0.4445 270)
			(size 0.1524 0.1524)
			(layers "F.Cu" "F.Mask" "F.Paste")
			(net "GND")
			(options
				(clearance outline)
				(anchor circle)
			)
			(primitives
				(gr_poly
					(pts
						(arc
							(start 0.3048 -0.2032)
							(mid 0.275042 -0.275042)
							(end 0.2032 -0.3048)
						)
						(arc
							(start -0.2032 -0.3048)
							(mid -0.275042 -0.275042)
							(end -0.3048 -0.2032)
						)
						(arc
							(start -0.3048 0.2032)
							(mid -0.275042 0.275042)
							(end -0.2032 0.3048)
						)
						(arc
							(start 0.2032 0.3048)
							(mid 0.275042 0.275042)
							(end 0.3048 0.2032)
						)
					)
					(width 0)
					(fill yes)
				)
			)
		)
	)
	(footprint ""
		(layer "F.Cu")
		(at 29.7942 -167.6908 -90)
		(property "Reference" "R165"
			(at 0 0 270)
			(layer "F.SilkS")
			(hide yes)
			(effects
				(font
					(size 1.27 1.27)
				)
			)
		)
		(property "Value" "0R2J-2-GP"
			(at 0.064008 -3.993896 270)
			(unlocked yes)
			(layer "F.Fab")
			(hide yes)
			(effects
				(font
					(size 1.016 1.016)
					(thickness 0.1524)
				)
			)
		)
		(property "Device Type" "R402H16"
			(at 0.064008 -5.517896 270)
			(unlocked yes)
			(layer "F.Fab")
			(hide yes)
			(effects
				(font
					(size 1.016 1.016)
					(thickness 0.1524)
				)
			)
		)
		(duplicate_pad_numbers_are_jumpers no)
		(fp_line
			(start -0.508 -0.9398)
			(end -0.508 0.9398)
			(stroke
				(width 0.1524)
				(type default)
			)
			(layer "F.SilkS")
		)
		(fp_line
			(start 0.508 -0.9398)
			(end -0.508 -0.9398)
			(stroke
				(width 0.1524)
				(type default)
			)
			(layer "F.SilkS")
		)
		(fp_rect
			(start -0.508 0.9398)
			(end 0.508 -0.9398)
			(stroke
				(width 0)
				(type default)
			)
			(fill no)
			(layer "F.CrtYd")
		)
		(fp_rect
			(start -0.508 0.9398)
			(end 0.508 -0.9398)
			(stroke
				(width 0)
				(type default)
			)
			(fill no)
			(layer "F.Fab")
		)
		(pad "1" smd custom
			(at 0 -0.4445 270)
			(size 0.1397 0.1397)
			(layers "F.Cu" "F.Mask" "F.Paste")
			(net "PWM_BUFFER_IN_FAN1_FAN2")
			(options
				(clearance outline)
				(anchor circle)
			)
			(primitives
				(gr_poly
					(pts
						(arc
							(start -0.1778 -0.2794)
							(mid -0.249642 -0.249642)
							(end -0.2794 -0.1778)
						)
						(arc
							(start -0.2794 0.1778)
							(mid -0.249642 0.249642)
							(end -0.1778 0.2794)
						)
						(arc
							(start 0.1778 0.2794)
							(mid 0.249642 0.249642)
							(end 0.2794 0.1778)
						)
						(arc
							(start 0.2794 -0.1778)
							(mid 0.249642 -0.249642)
							(end 0.1778 -0.2794)
						)
					)
					(width 0)
					(fill yes)
				)
			)
		)
		(pad "2" smd custom
			(at 0 0.4445 270)
			(size 0.1397 0.1397)
			(layers "F.Cu" "F.Mask" "F.Paste")
			(net "PWM_BUFFER_IN_FAN3_FAN4")
			(options
				(clearance outline)
				(anchor circle)
			)
			(primitives
				(gr_poly
					(pts
						(arc
							(start -0.1778 -0.2794)
							(mid -0.249642 -0.249642)
							(end -0.2794 -0.1778)
						)
						(arc
							(start -0.2794 0.1778)
							(mid -0.249642 0.249642)
							(end -0.1778 0.2794)
						)
						(arc
							(start 0.1778 0.2794)
							(mid 0.249642 0.249642)
							(end 0.2794 0.1778)
						)
						(arc
							(start 0.2794 -0.1778)
							(mid 0.249642 -0.249642)
							(end 0.1778 -0.2794)
						)
					)
					(width 0)
					(fill yes)
				)
			)
		)
	)
	(footprint ""
		(layer "F.Cu")
		(at 8.0518 -144.9832 -90)
		(property "Reference" "R64"
			(at 0 0 270)
			(layer "F.SilkS")
			(hide yes)
			(effects
				(font
					(size 1.27 1.27)
				)
			)
		)
		(property "Value" "4K7R2F-GP"
			(at 0.064008 -3.993896 270)
			(unlocked yes)
			(layer "F.Fab")
			(hide yes)
			(effects
				(font
					(size 1.016 1.016)
					(thickness 0.1524)
				)
			)
		)
		(property "Device Type" "R402H16"
			(at 0.064008 -5.517896 270)
			(unlocked yes)
			(layer "F.Fab")
			(hide yes)
			(effects
				(font
					(size 1.016 1.016)
					(thickness 0.1524)
				)
			)
		)
		(duplicate_pad_numbers_are_jumpers no)
		(fp_line
			(start -0.508 -0.9398)
			(end -0.508 0.9398)
			(stroke
				(width 0.1524)
				(type default)
			)
			(layer "F.SilkS")
		)
		(fp_line
			(start 0.508 -0.9398)
			(end -0.508 -0.9398)
			(stroke
				(width 0.1524)
				(type default)
			)
			(layer "F.SilkS")
		)
		(fp_rect
			(start -0.508 0.9398)
			(end 0.508 -0.9398)
			(stroke
				(width 0)
				(type default)
			)
			(fill no)
			(layer "F.CrtYd")
		)
		(fp_rect
			(start -0.508 0.9398)
			(end 0.508 -0.9398)
			(stroke
				(width 0)
				(type default)
			)
			(fill no)
			(layer "F.Fab")
		)
		(pad "1" smd custom
			(at 0 -0.4445 270)
			(size 0.1397 0.1397)
			(layers "F.Cu" "F.Mask" "F.Paste")
			(net "P12V")
			(options
				(clearance outline)
				(anchor circle)
			)
			(primitives
				(gr_poly
					(pts
						(arc
							(start -0.1778 -0.2794)
							(mid -0.249642 -0.249642)
							(end -0.2794 -0.1778)
						)
						(arc
							(start -0.2794 0.1778)
							(mid -0.249642 0.249642)
							(end -0.1778 0.2794)
						)
						(arc
							(start 0.1778 0.2794)
							(mid 0.249642 0.249642)
							(end 0.2794 0.1778)
						)
						(arc
							(start 0.2794 -0.1778)
							(mid 0.249642 -0.249642)
							(end 0.1778 -0.2794)
						)
					)
					(width 0)
					(fill yes)
				)
			)
		)
		(pad "2" smd custom
			(at 0 0.4445 270)
			(size 0.1397 0.1397)
			(layers "F.Cu" "F.Mask" "F.Paste")
			(net "PWM_OUT_FAN5_NET")
			(options
				(clearance outline)
				(anchor circle)
			)
			(primitives
				(gr_poly
					(pts
						(arc
							(start -0.1778 -0.2794)
							(mid -0.249642 -0.249642)
							(end -0.2794 -0.1778)
						)
						(arc
							(start -0.2794 0.1778)
							(mid -0.249642 0.249642)
							(end -0.1778 0.2794)
						)
						(arc
							(start 0.1778 0.2794)
							(mid 0.249642 0.249642)
							(end 0.2794 0.1778)
						)
						(arc
							(start 0.2794 -0.1778)
							(mid 0.249642 -0.249642)
							(end 0.1778 -0.2794)
						)
					)
					(width 0)
					(fill yes)
				)
			)
		)
	)
)
